# TIMECARD (Time Appliance Project (Time Card)) — schematic netlist excerpt (pin names and nets, part order shuffled) for the footprints in the layout excerpt that follows; sources: Cadence DE-HDL packaged netlist, KiCad conversion of R4006-B0001-02_R01.brd

C55  CAPACITOR  18PF 25V 5%  pkg SMC_0201R  page 28 : \1\ = XP3R3V_COMP ; \2\ = XP3R3V_AGND
R486  RESISTOR  33OHM 1%  pkg SMC_0402R_H016  page 24 : \1\ = FT4232_MUX3_SEL ; \2\ = MUX3_SEL

(kicad_pcb
	(version 20260206)
	(generator "pcbnew")
	(generator_version "10.0")
	(general
		(thickness 1.6)
		(legacy_teardrops no)
	)
	(paper "A4")
	(title_block
		(title "timecard-production-celestica-r4006 — R4006-B0001-02_R01.brd")
		(comment 1 "Time Appliance Project (Time Card) / footprints 427-428 of 1113")
	)
	(layers
		(0 "F.Cu" signal "TOP")
		(4 "In1.Cu" signal "L02_GND1")
		(6 "In2.Cu" signal "L03_SIG1")
		(8 "In3.Cu" signal "L04_GND2")
		(10 "In4.Cu" signal "L05_VCC1")
		(12 "In5.Cu" signal "L06_VCC2")
		(14 "In6.Cu" signal "L07_GND3")
		(16 "In7.Cu" signal "L08_SIG2")
		(18 "In8.Cu" signal "L09_GND4")
		(2 "B.Cu" signal "BOTTOM")
		(9 "F.Adhes" user "F.Adhesive")
		(11 "B.Adhes" user "B.Adhesive")
		(13 "F.Paste" user "Package Geometry/Pastemask Top")
		(15 "B.Paste" user "Package Geometry/Pastemask Bottom")
		(5 "F.SilkS" user "Ref Des/Silkscreen Top")
		(7 "B.SilkS" user "Ref Des/Silkscreen Bottom")
		(1 "F.Mask" user "Board Geometry/Soldermask Top")
		(3 "B.Mask" user "Board Geometry/Soldermask Bottom")
		(17 "Dwgs.User" user "User.Drawings")
		(19 "Cmts.User" user "User.Comments")
		(21 "Eco1.User" user "User.Eco1")
		(23 "Eco2.User" user "User.Eco2")
		(25 "Edge.Cuts" user "Board Geometry/Outline")
		(27 "Margin" user)
		(31 "F.CrtYd" user "Package Geometry/Place Bound Top")
		(29 "B.CrtYd" user "Package Geometry/Place Bound Bottom")
		(35 "F.Fab" user "Ref Des/Assembly Top")
		(33 "B.Fab" user "Ref Des/Assembly Bottom")
	)
	(footprint ""
		(layer "F.Cu")
		(at 119.761 -23.241)
		(property "Reference" "R486"
			(at -2.794 0.54737 0)
			(unlocked yes)
			(layer "F.SilkS")
			(effects
				(font
					(size 0.7874 0.5842)
					(thickness 0.1524)
				)
			)
		)
		(property "Value" "VAL*"
			(at 0.02032 2.13233 0)
			(unlocked yes)
			(layer "F.Fab")
			(hide yes)
			(effects
				(font
					(size 0.7874 0.5842)
					(thickness 0.1524)
				)
			)
		)
		(property "Tolerance" "TOL*"
			(at 0.044704 3.05435 0)
			(unlocked yes)
			(layer "Cmts.User")
			(hide yes)
			(effects
				(font
					(size 0.7874 0.5842)
					(thickness 0.1524)
				)
			)
		)
		(property "User Part Number" "PARTNUM*"
			(at 0.02032 4.024884 0)
			(unlocked yes)
			(layer "Cmts.User")
			(hide yes)
			(effects
				(font
					(size 0.7874 0.5842)
					(thickness 0.1524)
				)
			)
		)
		(property "Device Type" "RESISTOR-G155-133R0-01,33OHM,1%"
			(at 0.008382 1.210564 0)
			(unlocked yes)
			(layer "F.Fab")
			(hide yes)
			(effects
				(font
					(size 0.7874 0.5842)
					(thickness 0.1524)
				)
			)
		)
		(duplicate_pad_numbers_are_jumpers no)
		(fp_line
			(start -1.143 -0.5588)
			(end -1.143 0.5588)
			(stroke
				(width 0.1)
				(type default)
			)
			(layer "F.SilkS")
		)
		(fp_line
			(start -1.143 0.5588)
			(end 1.143 0.5588)
			(stroke
				(width 0.1)
				(type default)
			)
			(layer "F.SilkS")
		)
		(fp_line
			(start 1.143 -0.5588)
			(end -1.143 -0.5588)
			(stroke
				(width 0.1)
				(type default)
			)
			(layer "F.SilkS")
		)
		(fp_line
			(start 1.143 0.5588)
			(end 1.143 -0.5588)
			(stroke
				(width 0.1)
				(type default)
			)
			(layer "F.SilkS")
		)
		(fp_poly
			(pts
				(xy -1.143 0.5588) (xy 1.143 0.5588) (xy 1.143 -0.5588) (xy -1.143 -0.5588)
			)
			(stroke
				(width 0)
				(type default)
			)
			(fill no)
			(layer "F.CrtYd")
		)
		(fp_line
			(start -0.508 -0.3048)
			(end -0.508 0.3048)
			(stroke
				(width 0.1)
				(type default)
			)
			(layer "F.Fab")
		)
		(fp_line
			(start -0.508 0.3048)
			(end 0.508 0.3048)
			(stroke
				(width 0.1)
				(type default)
			)
			(layer "F.Fab")
		)
		(fp_line
			(start 0.508 -0.3048)
			(end -0.508 -0.3048)
			(stroke
				(width 0.1)
				(type default)
			)
			(layer "F.Fab")
		)
		(fp_line
			(start 0.508 0.3048)
			(end 0.508 -0.3048)
			(stroke
				(width 0.1)
				(type default)
			)
			(layer "F.Fab")
		)
		(pad "1" smd rect
			(at -0.5334 0)
			(size 0.7112 0.6096)
			(layers "F.Cu" "F.Mask" "F.Paste")
			(net "FT4232_MUX3_SEL")
		)
		(pad "2" smd rect
			(at 0.5334 0)
			(size 0.7112 0.6096)
			(layers "F.Cu" "F.Mask" "F.Paste")
			(net "MUX3_SEL")
		)
		(zone
			(layer "F.Cu")
			(hatch none 0.5)
			(connect_pads
				(clearance 0)
			)
			(min_thickness 0.25)
			(keepout
				(tracks allowed)
				(vias not_allowed)
				(pads allowed)
				(copperpour not_allowed)
				(footprints allowed)
			)
			(placement
				(enabled no)
				(sheetname "")
			)
			(fill
				(thermal_gap 0.5)
				(thermal_bridge_width 0.5)
				(island_removal_mode 0)
			)
			(polygon
				(pts
					(xy 119.6848 -22.9362) (xy 119.8372 -22.9362) (xy 119.8372 -23.5458) (xy 119.6848 -23.5458)
				)
			)
		)
		(zone
			(layer "F.Cu")
			(hatch none 0.5)
			(connect_pads
				(clearance 0)
			)
			(min_thickness 0.25)
			(keepout
				(tracks not_allowed)
				(vias allowed)
				(pads allowed)
				(copperpour not_allowed)
				(footprints allowed)
			)
			(placement
				(enabled no)
				(sheetname "")
			)
			(fill
				(thermal_gap 0.5)
				(thermal_bridge_width 0.5)
				(island_removal_mode 0)
			)
			(polygon
				(pts
					(xy 119.6848 -22.9362) (xy 119.8372 -22.9362) (xy 119.8372 -23.5458) (xy 119.6848 -23.5458)
				)
			)
		)
	)
	(footprint ""
		(layer "F.Cu")
		(at 89.8652 -100.2538)
		(property "Reference" "C55"
			(at 1.905 0.16637 0)
			(unlocked yes)
			(layer "F.SilkS")
			(effects
				(font
					(size 0.7874 0.5842)
					(thickness 0.1524)
				)
			)
		)
		(property "Value" "VAL*"
			(at 0.193548 2.13614 0)
			(unlocked yes)
			(layer "F.Fab")
			(hide yes)
			(effects
				(font
					(size 0.7874 0.5842)
					(thickness 0.1524)
				)
			)
		)
		(property "User Part Number" "PARTNUM*"
			(at 0.216154 4.185666 0)
			(unlocked yes)
			(layer "Cmts.User")
			(hide yes)
			(effects
				(font
					(size 0.7874 0.5842)
					(thickness 0.1524)
				)
			)
		)
		(property "Device Type" "CAPACITOR-G104-0A180-FJ,18PF,5%"
			(at 0.184404 1.180592 0)
			(unlocked yes)
			(layer "F.Fab")
			(hide yes)
			(effects
				(font
					(size 0.7874 0.5842)
					(thickness 0.1524)
				)
			)
		)
		(property "Tolerance" "TOL*"
			(at 0.216154 3.1496 0)
			(unlocked yes)
			(layer "Cmts.User")
			(hide yes)
			(effects
				(font
					(size 0.7874 0.5842)
					(thickness 0.1524)
				)
			)
		)
		(duplicate_pad_numbers_are_jumpers no)
		(fp_line
			(start -0.671322 -0.4445)
			(end 0.671322 -0.4445)
			(stroke
				(width 0.1)
				(type default)
			)
			(layer "F.SilkS")
		)
		(fp_line
			(start -0.671322 0.4445)
			(end -0.671322 -0.4445)
			(stroke
				(width 0.1)
				(type default)
			)
			(layer "F.SilkS")
		)
		(fp_line
			(start 0.671322 -0.4445)
			(end 0.671322 0.4445)
			(stroke
				(width 0.1)
				(type default)
			)
			(layer "F.SilkS")
		)
		(fp_line
			(start 0.671322 0.4445)
			(end -0.671322 0.4445)
			(stroke
				(width 0.1)
				(type default)
			)
			(layer "F.SilkS")
		)
		(fp_rect
			(start -0.671322 0.4445)
			(end 0.671322 -0.4445)
			(stroke
				(width 0)
				(type default)
			)
			(fill no)
			(layer "F.CrtYd")
		)
		(fp_line
			(start -0.31496 -0.1651)
			(end -0.31496 0.1651)
			(stroke
				(width 0.1)
				(type default)
			)
			(layer "F.Fab")
		)
		(fp_line
			(start -0.31496 0.1651)
			(end 0.31496 0.1651)
			(stroke
				(width 0.1)
				(type default)
			)
			(layer "F.Fab")
		)
		(fp_line
			(start 0.31496 -0.1651)
			(end -0.31496 -0.1651)
			(stroke
				(width 0.1)
				(type default)
			)
			(layer "F.Fab")
		)
		(fp_line
			(start 0.31496 0.1651)
			(end 0.31496 -0.1651)
			(stroke
				(width 0.1)
				(type default)
			)
			(layer "F.Fab")
		)
		(pad "1" smd rect
			(at -0.264922 0)
			(size 0.3048 0.381)
			(layers "F.Cu" "F.Mask" "F.Paste")
			(net "XP3R3V_COMP")
		)
		(pad "2" smd rect
			(at 0.264922 0)
			(size 0.3048 0.381)
			(layers "F.Cu" "F.Mask" "F.Paste")
			(net "XP3R3V_AGND")
		)
		(zone
			(layer "F.Cu")
			(hatch none 0.5)
			(connect_pads
				(clearance 0)
			)
			(min_thickness 0.25)
			(keepout
				(tracks allowed)
				(vias not_allowed)
				(pads allowed)
				(copperpour not_allowed)
				(footprints allowed)
			)
			(placement
				(enabled no)
				(sheetname "")
			)
			(fill
				(thermal_gap 0.5)
				(thermal_bridge_width 0.5)
				(island_removal_mode 0)
			)
			(polygon
				(pts
					(xy 89.752678 -100.0633) (xy 89.977722 -100.0633) (xy 89.977722 -100.4443) (xy 89.752678 -100.4443)
				)
			)
		)
	)
)
